%FSTAX23Y23*%
%MOIN*%
%SFA1B1*%

%IPPOS*%
%ADD9500C,0.008000*%
%ADD9501C,0.021660*%
%ADD9502C,0.029920*%
%ADD9503C,0.030000*%
%ADD9504C,0.041340*%
%ADD9505C,0.050000*%
%ADD9506C,0.060000*%
%ADD9507C,0.064960*%
%ADD9508C,0.068000*%
%ADD9509C,0.070870*%
%ADD9510C,0.118110*%
%ADD9511C,0.125980*%
%ADD9512C,0.035430*%
%ADD9513C,0.065980*%
%ADD9514C,0.118110*%
%ADD9515C,0.125200*%
%LNgrandmaster-roundholes-1*%
%LPD*%
G54D9500*
X03642Y00636D03*
X03603Y00682D03*
X02893Y00795D03*
X02862D03*
X02826D03*
X02799D03*
X02759D03*
X02732D03*
X02692D03*
X02665D03*
X02625D03*
X02598D03*
X02606Y00931D03*
X02622Y00976D03*
X02649D03*
X02681D03*
X02708D03*
X0274D03*
X02767D03*
X02799D03*
X02826D03*
X02933Y00953D03*
X02901Y01095D03*
X02842D03*
X02784Y01094D03*
X02724Y01093D03*
X02665Y01092D03*
X02606Y01091D03*
X02508Y0109D03*
X02409Y01088D03*
X02311Y0109D03*
X02311Y00934D03*
X02409Y00932D03*
X02478Y00937D03*
X02508Y00931D03*
X02511Y00405D03*
X02469Y0041D03*
X02389Y00405D03*
X0235D03*
X02413Y00279D03*
X02444D03*
X02447Y00242D03*
X02546Y00244D03*
X02578Y00279D03*
X0261D03*
X02636Y00247D03*
X02748Y00282D03*
X02779Y00279D03*
X02799Y00251D03*
X02878Y00249D03*
X02905Y00279D03*
X02937Y00279D03*
X02957Y00251D03*
X03097D03*
X03019Y00405D03*
X0298Y00409D03*
X02854Y00405D03*
X02821Y00407D03*
X02704Y00405D03*
X02665D03*
X02309Y00246D03*
X02151Y00255D03*
Y00287D03*
X02112D03*
Y00255D03*
X02076D03*
Y00287D03*
X02034Y00246D03*
X01916Y00244D03*
X01872Y00255D03*
X01852D03*
X01832D03*
Y00287D03*
X01852D03*
X01872D03*
X01797Y00355D03*
X01256Y00942D03*
X01004Y00906D03*
X0099Y00687D03*
X00654Y0079D03*
X00655Y01028D03*
X00996Y01187D03*
X01008Y0143D03*
X01242Y01472D03*
X01671Y01497D03*
X01718D03*
X01719Y01536D03*
X01714Y01595D03*
X0167D03*
Y01694D03*
X01721D03*
X01718Y01792D03*
X01671D03*
X01675Y01891D03*
X01721Y0189D03*
Y01989D03*
X01674D03*
X01568Y02067D03*
X01619Y02121D03*
X01754Y02126D03*
X01248Y02D03*
X01009Y01956D03*
X00988Y01717D03*
X00654Y01839D03*
Y02073D03*
Y02365D03*
X00653Y02593D03*
X0102Y02481D03*
X01261Y02482D03*
X00937Y02317D03*
X00996Y02256D03*
X01393Y01816D03*
X01671Y01399D03*
X01716D03*
X01798Y01304D03*
X01567Y01285D03*
X00654Y01314D03*
X00653Y01551D03*
X01897Y01516D03*
X01893Y01693D03*
X01822Y01674D03*
X01879Y01811D03*
X01884Y02071D03*
X02299Y01916D03*
X02384Y01941D03*
X02409Y01967D03*
Y02283D03*
Y02314D03*
X0245Y02282D03*
X02475Y02291D03*
X02499Y02236D03*
X02579Y02281D03*
X02581Y02308D03*
X02645Y02274D03*
X02665Y02291D03*
X02702Y02289D03*
X02726Y02293D03*
X02685Y02311D03*
X02803Y02307D03*
X02871Y02297D03*
X02841Y02263D03*
X02942Y02286D03*
X02985Y02287D03*
X0292Y02428D03*
X02894Y02431D03*
X02948Y02456D03*
X02958Y02621D03*
X02881Y02566D03*
X02821Y02601D03*
X02783Y02568D03*
X02685D03*
X02586Y02569D03*
X02599Y02436D03*
X02575Y02412D03*
X02488Y02413D03*
X02475Y02456D03*
X02525Y02463D03*
X02624Y02461D03*
X02783Y02429D03*
X02692Y02721D03*
X02494Y02696D03*
Y02661D03*
X02429Y02621D03*
X02409Y02579D03*
X02321Y02586D03*
X02231Y02584D03*
X02252Y02613D03*
X02272Y02463D03*
X02404Y02412D03*
X0233Y02215D03*
X02253Y02279D03*
X02146Y02753D03*
X02394Y0272D03*
X02419Y02788D03*
X02579Y0179D03*
X02549Y01755D03*
X02604Y01734D03*
X02626Y0177D03*
X02666Y0164D03*
X02643Y01616D03*
X02719Y01591D03*
X02694Y01481D03*
X02894Y01561D03*
X02919Y01536D03*
X03056Y01811D03*
X03197Y01714D03*
X03224Y01661D03*
X03252Y01661D03*
X03329Y01826D03*
X03298Y01971D03*
X03342Y02263D03*
X03379Y01386D03*
Y01336D03*
X02502Y01316D03*
X02446Y01437D03*
X02274Y01506D03*
X02206Y01298D03*
X02059Y01386D03*
X02083Y01411D03*
X02028Y01361D03*
X02004Y01336D03*
X03404Y01363D03*
X03407Y01411D03*
X03406Y01461D03*
X03413Y01573D03*
X0341Y01713D03*
X03414Y01805D03*
X03392Y01871D03*
X03439Y0187D03*
X03554Y01891D03*
Y01841D03*
Y01941D03*
Y01991D03*
X03571Y02033D03*
Y02058D03*
X03719Y01996D03*
Y01921D03*
Y01766D03*
X03718Y01713D03*
X03724Y01675D03*
X03773Y01666D03*
X03803Y01691D03*
X03804Y0184D03*
X03944Y01816D03*
X04064Y01796D03*
X04134Y01751D03*
X04131Y01686D03*
X04134Y01651D03*
X04151Y01623D03*
X04179Y01601D03*
X04034Y01546D03*
X03994Y01551D03*
X03969Y01552D03*
X03924Y01536D03*
X03894Y01566D03*
X03864Y01511D03*
X03834Y01481D03*
X03732Y01418D03*
X03549Y01413D03*
Y01441D03*
X03594Y01514D03*
X0359Y01662D03*
X03589Y01711D03*
X03996D03*
X03968Y01671D03*
X04064Y01511D03*
X04039Y02406D03*
X04064Y02722D03*
X0396Y02724D03*
X04234Y02725D03*
X04339D03*
X04503Y02789D03*
X04794Y02808D03*
X03623Y02587D03*
X03498Y02341D03*
X05577Y02214D03*
X05634Y02236D03*
X06048Y02171D03*
X06004Y02434D03*
X06274Y02391D03*
X06284Y02501D03*
X06397D03*
X06398Y02453D03*
X06396Y02556D03*
X06397Y0261D03*
X06398Y02657D03*
X06424Y02181D03*
X06395Y02111D03*
X06607Y02176D03*
X06699Y01881D03*
X06685Y01828D03*
X06601Y01777D03*
X06602Y01722D03*
Y01672D03*
Y01612D03*
X06548Y01531D03*
X06628Y01372D03*
X06844Y01661D03*
X06974Y01939D03*
X06949Y02095D03*
X06626Y03032D03*
X06647Y03129D03*
X06648Y03341D03*
X06509Y03456D03*
X06479Y03426D03*
X06447Y03396D03*
X06409Y03371D03*
X06354Y03331D03*
X06334Y03266D03*
X06282Y03226D03*
X06309Y03199D03*
X06339Y03151D03*
X06304Y03121D03*
X06439Y03191D03*
X06476Y03231D03*
X06444Y03291D03*
X06456Y03009D03*
X06372Y02909D03*
X06253D03*
X06294Y03701D03*
X05994Y03552D03*
X05733Y03556D03*
X05676Y03546D03*
X05274Y03511D03*
X05267Y04088D03*
X0491Y04203D03*
X04754Y04115D03*
X04387Y04206D03*
X04194Y03884D03*
X04085Y03892D03*
X04039Y03784D03*
X04049Y03665D03*
X0412Y03594D03*
X04254Y03776D03*
X0383Y03762D03*
X03829Y03806D03*
X03699Y03836D03*
Y03751D03*
X03539Y03806D03*
X03531Y0366D03*
X03424Y03636D03*
X03436Y03457D03*
X03469Y03456D03*
X03394Y03447D03*
X03529Y03481D03*
X03622Y03486D03*
X03653Y03293D03*
X03744Y03261D03*
Y03342D03*
X03806Y03235D03*
X03799Y03201D03*
X03829Y03176D03*
X03854Y03151D03*
X0388Y03109D03*
X03939Y03121D03*
X04068Y03135D03*
X04114D03*
X04152D03*
X04208D03*
X04272D03*
X04333D03*
X04431D03*
X04477D03*
X03717Y03072D03*
X03491Y03103D03*
Y03297D03*
X03542Y03319D03*
X03504Y04086D03*
X03395Y04222D03*
X03777Y04023D03*
X03269Y03788D03*
X03219Y03806D03*
X03239Y03596D03*
X03358Y03448D03*
X03302Y03344D03*
X0333Y03301D03*
X03263Y03303D03*
X0323Y03235D03*
X03188Y03187D03*
X03183Y03135D03*
X03275Y03141D03*
X03277Y02963D03*
X03197Y0297D03*
X03344Y02996D03*
X03368Y0305D03*
X0337Y02888D03*
X03374Y03273D03*
X03068Y03395D03*
X02993Y03751D03*
X03014Y03831D03*
X0286Y03787D03*
X02722Y03786D03*
X02724Y03729D03*
X02679Y03661D03*
X02674Y03501D03*
X02724Y03521D03*
X02774Y03566D03*
X02799Y03616D03*
X02579Y03486D03*
X02634Y03406D03*
X0259Y03288D03*
X02591Y03186D03*
X02462Y03172D03*
X02414Y03199D03*
X02418Y03118D03*
X02413Y03295D03*
X02321Y03361D03*
X02259Y03261D03*
X02205Y032D03*
X02234Y03506D03*
X02254Y03536D03*
X02389Y03481D03*
X02434Y03546D03*
X02139Y03611D03*
Y03738D03*
X02258Y03741D03*
X02029Y03836D03*
X02004Y03816D03*
X02059Y03871D03*
X02084Y03896D03*
X02146Y04103D03*
X02253Y04086D03*
X0229Y04217D03*
X02353Y04017D03*
X01903Y04018D03*
X01849Y03701D03*
X01884Y03601D03*
X02473Y0298D03*
X02631Y02876D03*
X0257Y04283D03*
X02888Y04221D03*
X01779Y04156D03*
X01749Y0411D03*
X01691Y04079D03*
X01569Y04171D03*
X01557Y04229D03*
X01345Y04175D03*
X01294Y04256D03*
X01408Y0398D03*
X0144Y03557D03*
X01549Y03621D03*
X01574Y03596D03*
X01754Y03661D03*
X01726Y04329D03*
X01788D03*
X01459Y03147D03*
G54D9501*
X02203Y00958D03*
X0299D03*
X01696Y01309D03*
Y02097D03*
X02203Y02438D03*
X0299D03*
X03571Y02097D03*
Y01309D03*
G54D9502*
X02422Y03082D03*
Y03239D03*
Y03443D03*
Y03601D03*
G54D9503*
X02043Y04057D03*
Y04157D03*
Y04257D03*
X01457Y04253D03*
Y04153D03*
Y04053D03*
G54D9504*
X05127Y01007D03*
X05327D03*
X04927D03*
X04327D03*
Y02307D03*
X04727D03*
X04927D03*
X05127D03*
X05327D03*
G54D9505*
X05578Y0089D03*
X03979D03*
Y02489D03*
X04062Y02595D03*
X0418D03*
X04298D03*
X05578Y02489D03*
Y01689D03*
G54D9506*
X00199Y00906D03*
Y01431D03*
Y01956D03*
Y02481D03*
G54D9507*
X05723Y03844D03*
Y04025D03*
G54D9508*
X00299Y00806D03*
Y01006D03*
X00099D03*
Y00806D03*
Y01331D03*
Y01531D03*
Y01856D03*
Y02056D03*
Y02381D03*
Y02581D03*
X00299D03*
Y02381D03*
Y02056D03*
Y01856D03*
Y01531D03*
Y01331D03*
G54D9509*
X06569Y03589D03*
X06734D03*
X069D03*
Y03806D03*
X06734D03*
X06569D03*
G54D9510*
X03617Y00916D03*
X01652D03*
X01651Y02486D03*
X03617D03*
G54D9511*
X02531Y0283D03*
Y03853D03*
X00149D03*
Y0283D03*
G54D9512*
X03784Y04126D03*
X03958D03*
G54D9513*
X02994Y04086D03*
X03294D03*
G54D9514*
X06569Y04093D03*
X069D03*
G54D9515*
X00285Y00368D03*
Y04152D03*
M02*